(kicad_pcb
	(version 20260206)
	(generator "pcbnew")
	(generator_version "10.0")
	(general
		(thickness 1.6)
		(legacy_teardrops no)
	)
	(paper "A4")
	(title_block
		(title "Wiwynn_Tioga_Pass_MB.brd")
		(comment 1 "Tioga Pass / footprints 2491-2497 of 4770")
	)
	(layers
		(0 "F.Cu" signal "TOP")
		(4 "In1.Cu" signal "L2GND")
		(6 "In2.Cu" signal "L3")
		(8 "In3.Cu" signal "L4GND")
		(10 "In4.Cu" signal "L5")
		(12 "In5.Cu" signal "L6GND")
		(14 "In6.Cu" signal "L7VCC")
		(16 "In7.Cu" signal "L8VCC")
		(18 "In8.Cu" signal "L9GND")
		(20 "In9.Cu" signal "L10")
		(22 "In10.Cu" signal "L11GND")
		(24 "In11.Cu" signal "L12")
		(26 "In12.Cu" signal "L13GND")
		(2 "B.Cu" signal "BOTTOM")
		(9 "F.Adhes" user "F.Adhesive")
		(11 "B.Adhes" user "B.Adhesive")
		(13 "F.Paste" user "Package Geometry/Pastemask Top")
		(15 "B.Paste" user "Package Geometry/Pastemask Bottom")
		(5 "F.SilkS" user "Ref Des/Silkscreen Top")
		(7 "B.SilkS" user "Ref Des/Silkscreen Bottom")
		(1 "F.Mask" user "Board Geometry/Soldermask Top")
		(3 "B.Mask" user "Board Geometry/Soldermask Bottom")
		(17 "Dwgs.User" user "User.Drawings")
		(19 "Cmts.User" user "User.Comments")
		(21 "Eco1.User" user "User.Eco1")
		(23 "Eco2.User" user "User.Eco2")
		(25 "Edge.Cuts" user "Board Geometry/Outline")
		(27 "Margin" user)
		(31 "F.CrtYd" user "Package Geometry/Place Bound Top")
		(29 "B.CrtYd" user "Package Geometry/Place Bound Bottom")
		(35 "F.Fab" user "Ref Des/Assembly Top")
		(33 "B.Fab" user "Ref Des/Assembly Bottom")
	)
	(footprint ""
		(layer "B.Cu")
		(at 275.389086 -79.60614 180)
		(property "Reference" "C5P10"
			(at 0 0 0)
			(layer "B.SilkS")
			(hide yes)
			(effects
				(font
					(size 1.27 1.27)
				)
				(justify mirror)
			)
		)
		(property "Value" ""
			(at 0 0 0)
			(layer "B.Fab")
			(effects
				(font
					(size 1.27 1.27)
				)
				(justify mirror)
			)
		)
		(duplicate_pad_numbers_are_jumpers no)
		(fp_poly
			(pts
				(xy 0.7239 -0.2159) (xy -0.7239 -0.2159) (xy -0.7239 1.9939) (xy 0.7239 1.9939)
			)
			(stroke
				(width 0)
				(type default)
			)
			(fill no)
			(layer "B.CrtYd")
		)
		(fp_line
			(start 0.7239 1.9939)
			(end -0.7239 1.9939)
			(stroke
				(width 0.1)
				(type default)
			)
			(layer "B.Fab")
		)
		(fp_line
			(start 0.7239 -0.2159)
			(end 0.7239 1.9939)
			(stroke
				(width 0.1)
				(type default)
			)
			(layer "B.Fab")
		)
		(fp_line
			(start -0.7239 1.9939)
			(end -0.7239 -0.2159)
			(stroke
				(width 0.1)
				(type default)
			)
			(layer "B.Fab")
		)
		(fp_line
			(start -0.7239 -0.2159)
			(end 0.7239 -0.2159)
			(stroke
				(width 0.1)
				(type default)
			)
			(layer "B.Fab")
		)
		(pad "1" smd rect
			(at 0 0)
			(size 1.27 1.016)
			(layers "B.Cu" "B.Mask" "B.Paste")
			(net "PVCCMCP_CPU0")
		)
		(pad "2" smd rect
			(at 0 1.778)
			(size 1.27 1.016)
			(layers "B.Cu" "B.Mask" "B.Paste")
			(net "GND")
		)
		(zone
			(layer "B.Cu")
			(hatch none 0.5)
			(connect_pads
				(clearance 0)
			)
			(min_thickness 0.25)
			(keepout
				(tracks not_allowed)
				(vias allowed)
				(pads allowed)
				(copperpour not_allowed)
				(footprints allowed)
			)
			(placement
				(enabled no)
				(sheetname "")
			)
			(fill
				(thermal_gap 0.5)
				(thermal_bridge_width 0.5)
				(island_removal_mode 0)
			)
			(polygon
				(pts
					(xy 274.754086 -80.11414) (xy 276.024086 -80.11414) (xy 276.024086 -80.87614) (xy 274.754086 -80.87614)
				)
			)
		)
	)
	(footprint ""
		(layer "B.Cu")
		(at 88.392 -145.0086 90)
		(property "Reference" "C8L7"
			(at -1.848866 0.752348 90)
			(unlocked yes)
			(layer "B.SilkS")
			(effects
				(font
					(size 1.27 0.9652)
					(thickness 0.1524)
				)
				(justify mirror)
			)
		)
		(property "Value" ""
			(at 0 0 90)
			(layer "B.Fab")
			(effects
				(font
					(size 1.27 1.27)
				)
				(justify mirror)
			)
		)
		(duplicate_pad_numbers_are_jumpers no)
		(fp_rect
			(start 0.500126 1.598422)
			(end -0.500126 -0.201422)
			(stroke
				(width 0)
				(type default)
			)
			(fill no)
			(layer "B.CrtYd")
		)
		(fp_line
			(start 0.500126 -0.201422)
			(end -0.500126 -0.201422)
			(stroke
				(width 0.1)
				(type default)
			)
			(layer "B.Fab")
		)
		(fp_line
			(start -0.500126 -0.201422)
			(end -0.500126 1.598422)
			(stroke
				(width 0.1)
				(type default)
			)
			(layer "B.Fab")
		)
		(fp_line
			(start 0.500126 1.598422)
			(end 0.500126 -0.201422)
			(stroke
				(width 0.1)
				(type default)
			)
			(layer "B.Fab")
		)
		(fp_line
			(start -0.500126 1.598422)
			(end 0.500126 1.598422)
			(stroke
				(width 0.1)
				(type default)
			)
			(layer "B.Fab")
		)
		(pad "1" smd rect
			(at 0 0)
			(size 0.889 0.9906)
			(layers "B.Cu" "B.Mask" "B.Paste")
			(net "PVDDQ_KLM")
		)
		(pad "2" smd rect
			(at 0 1.397)
			(size 0.889 0.9906)
			(layers "B.Cu" "B.Mask" "B.Paste")
			(net "GND")
		)
		(zone
			(layer "B.Cu")
			(hatch none 0.5)
			(connect_pads
				(clearance 0)
			)
			(min_thickness 0.25)
			(keepout
				(tracks not_allowed)
				(vias allowed)
				(pads allowed)
				(copperpour not_allowed)
				(footprints allowed)
			)
			(placement
				(enabled no)
				(sheetname "")
			)
			(fill
				(thermal_gap 0.5)
				(thermal_bridge_width 0.5)
				(island_removal_mode 0)
			)
			(polygon
				(pts
					(xy 89.3445 -145.5039) (xy 88.8365 -145.5039) (xy 88.8365 -144.5133) (xy 89.3445 -144.5133)
				)
			)
		)
		(zone
			(layer "B.Cu")
			(hatch none 0.5)
			(connect_pads
				(clearance 0)
			)
			(min_thickness 0.25)
			(keepout
				(tracks allowed)
				(vias not_allowed)
				(pads allowed)
				(copperpour not_allowed)
				(footprints allowed)
			)
			(placement
				(enabled no)
				(sheetname "")
			)
			(fill
				(thermal_gap 0.5)
				(thermal_bridge_width 0.5)
				(island_removal_mode 0)
			)
			(polygon
				(pts
					(xy 89.3445 -145.5039) (xy 88.8365 -145.5039) (xy 88.8365 -144.5133) (xy 89.3445 -144.5133)
				)
			)
		)
	)
	(footprint ""
		(layer "B.Cu")
		(at 399.923 -55.118 180)
		(property "Reference" "R3T4"
			(at 0 0 0)
			(layer "B.SilkS")
			(hide yes)
			(effects
				(font
					(size 1.27 1.27)
				)
				(justify mirror)
			)
		)
		(property "Value" ""
			(at 0 0 0)
			(layer "B.Fab")
			(effects
				(font
					(size 1.27 1.27)
				)
				(justify mirror)
			)
		)
		(duplicate_pad_numbers_are_jumpers no)
		(fp_poly
			(pts
				(xy 0.2794 -0.1016) (xy -0.2794 -0.1016) (xy -0.2794 0.9906) (xy 0.2794 0.9906)
			)
			(stroke
				(width 0)
				(type default)
			)
			(fill no)
			(layer "B.CrtYd")
		)
		(fp_line
			(start 0.2794 0.9906)
			(end -0.2794 0.9906)
			(stroke
				(width 0.1)
				(type default)
			)
			(layer "B.Fab")
		)
		(fp_line
			(start 0.2794 -0.1016)
			(end 0.2794 0.9906)
			(stroke
				(width 0.1)
				(type default)
			)
			(layer "B.Fab")
		)
		(fp_line
			(start -0.2794 0.9906)
			(end -0.2794 -0.1016)
			(stroke
				(width 0.1)
				(type default)
			)
			(layer "B.Fab")
		)
		(fp_line
			(start -0.2794 -0.1016)
			(end 0.2794 -0.1016)
			(stroke
				(width 0.1)
				(type default)
			)
			(layer "B.Fab")
		)
		(pad "1" smd rect
			(at 0 0)
			(size 0.508 0.508)
			(layers "B.Cu" "B.Mask" "B.Paste")
			(net "P3V3_STBY")
		)
		(pad "2" smd rect
			(at 0 0.889)
			(size 0.508 0.508)
			(layers "B.Cu" "B.Mask" "B.Paste")
			(net "PU_BIOS_SPI_HOLD1_N")
		)
		(zone
			(layer "B.Cu")
			(hatch none 0.5)
			(connect_pads
				(clearance 0)
			)
			(min_thickness 0.25)
			(keepout
				(tracks not_allowed)
				(vias allowed)
				(pads allowed)
				(copperpour not_allowed)
				(footprints allowed)
			)
			(placement
				(enabled no)
				(sheetname "")
			)
			(fill
				(thermal_gap 0.5)
				(thermal_bridge_width 0.5)
				(island_removal_mode 0)
			)
			(polygon
				(pts
					(xy 399.669 -55.753) (xy 400.177 -55.753) (xy 400.177 -55.372) (xy 399.669 -55.372)
				)
			)
		)
		(zone
			(layer "B.Cu")
			(hatch none 0.5)
			(connect_pads
				(clearance 0)
			)
			(min_thickness 0.25)
			(keepout
				(tracks allowed)
				(vias not_allowed)
				(pads allowed)
				(copperpour not_allowed)
				(footprints allowed)
			)
			(placement
				(enabled no)
				(sheetname "")
			)
			(fill
				(thermal_gap 0.5)
				(thermal_bridge_width 0.5)
				(island_removal_mode 0)
			)
			(polygon
				(pts
					(xy 399.669 -55.372) (xy 400.177 -55.372) (xy 400.177 -55.753) (xy 399.669 -55.753)
				)
			)
		)
	)
	(footprint ""
		(layer "B.Cu")
		(at 373.4308 -44.8818 90)
		(property "Reference" "R2T36"
			(at 0 0 90)
			(layer "B.SilkS")
			(hide yes)
			(effects
				(font
					(size 1.27 1.27)
				)
				(justify mirror)
			)
		)
		(property "Value" "*"
			(at -0.064008 -4.108196 90)
			(unlocked yes)
			(layer "B.Fab")
			(hide yes)
			(effects
				(font
					(size 1.27 1.016)
					(thickness 0.1524)
				)
				(justify mirror)
			)
		)
		(property "Device Type" "374R2F-1-GP_SMD-RG-374R2F-1-GPA"
			(at -0.064008 -5.632196 90)
			(unlocked yes)
			(layer "B.Fab")
			(hide yes)
			(effects
				(font
					(size 1.27 1.016)
					(thickness 0.1524)
				)
				(justify mirror)
			)
		)
		(duplicate_pad_numbers_are_jumpers no)
		(fp_line
			(start 0.508 -0.9398)
			(end 0.508 0.9398)
			(stroke
				(width 0.1524)
				(type default)
			)
			(layer "B.SilkS")
		)
		(fp_line
			(start -0.508 -0.9398)
			(end 0.508 -0.9398)
			(stroke
				(width 0.1524)
				(type default)
			)
			(layer "B.SilkS")
		)
		(fp_rect
			(start 0.508 0.9398)
			(end -0.508 -0.9398)
			(stroke
				(width 0)
				(type default)
			)
			(fill no)
			(layer "B.CrtYd")
		)
		(fp_rect
			(start 0.508 0.9398)
			(end -0.508 -0.9398)
			(stroke
				(width 0)
				(type default)
			)
			(fill no)
			(layer "B.Fab")
		)
		(pad "1" smd custom
			(at 0 -0.4445 270)
			(size 0.1397 0.1397)
			(layers "B.Cu" "B.Mask" "B.Paste")
			(net "P3V3")
			(options
				(clearance outline)
				(anchor circle)
			)
			(primitives
				(gr_poly
					(pts
						(arc
							(start -0.1778 0.2794)
							(mid -0.249642 0.249642)
							(end -0.2794 0.1778)
						)
						(arc
							(start -0.2794 -0.1778)
							(mid -0.249642 -0.249642)
							(end -0.1778 -0.2794)
						)
						(arc
							(start 0.1778 -0.2794)
							(mid 0.249642 -0.249642)
							(end 0.2794 -0.1778)
						)
						(arc
							(start 0.2794 0.1778)
							(mid 0.249642 0.249642)
							(end 0.1778 0.2794)
						)
					)
					(width 0)
					(fill yes)
				)
			)
		)
		(pad "2" smd custom
			(at 0 0.4445 270)
			(size 0.1397 0.1397)
			(layers "B.Cu" "B.Mask" "B.Paste")
			(net "P0V7_GTL2104_5_VREF")
			(options
				(clearance outline)
				(anchor circle)
			)
			(primitives
				(gr_poly
					(pts
						(arc
							(start -0.1778 0.2794)
							(mid -0.249642 0.249642)
							(end -0.2794 0.1778)
						)
						(arc
							(start -0.2794 -0.1778)
							(mid -0.249642 -0.249642)
							(end -0.1778 -0.2794)
						)
						(arc
							(start 0.1778 -0.2794)
							(mid 0.249642 -0.249642)
							(end 0.2794 -0.1778)
						)
						(arc
							(start 0.2794 0.1778)
							(mid 0.249642 0.249642)
							(end 0.1778 0.2794)
						)
					)
					(width 0)
					(fill yes)
				)
			)
		)
	)
	(footprint ""
		(layer "B.Cu")
		(at 372.51894 -153.956766)
		(property "Reference" "C3L1"
			(at 0 0 0)
			(layer "B.SilkS")
			(hide yes)
			(effects
				(font
					(size 1.27 1.27)
				)
				(justify mirror)
			)
		)
		(property "Value" "*"
			(at -1.1811 -2.8194 0)
			(unlocked yes)
			(layer "B.Fab")
			(hide yes)
			(effects
				(font
					(size 1.27 1.016)
					(thickness 0.1524)
				)
				(justify mirror)
			)
		)
		(property "Device Type" "SC1U10V2KX-4-GP_SMD-BCG6-SC1U1A"
			(at -1.1811 -4.3434 0)
			(unlocked yes)
			(layer "B.Fab")
			(hide yes)
			(effects
				(font
					(size 1.27 1.016)
					(thickness 0.1524)
				)
				(justify mirror)
			)
		)
		(duplicate_pad_numbers_are_jumpers no)
		(fp_rect
			(start 0.4318 0.9525)
			(end -0.4318 -0.9525)
			(stroke
				(width 0)
				(type default)
			)
			(fill no)
			(layer "B.CrtYd")
		)
		(fp_rect
			(start 0.4318 0.9525)
			(end -0.4318 -0.9525)
			(stroke
				(width 0)
				(type default)
			)
			(fill no)
			(layer "B.Fab")
		)
		(pad "1" smd custom
			(at 0 -0.4445 180)
			(size 0.1524 0.1524)
			(layers "B.Cu" "B.Mask" "B.Paste")
			(net "P5V_STBY")
			(options
				(clearance outline)
				(anchor circle)
			)
			(primitives
				(gr_poly
					(pts
						(arc
							(start 0.3048 0.2032)
							(mid 0.275042 0.275042)
							(end 0.2032 0.3048)
						)
						(arc
							(start -0.2032 0.3048)
							(mid -0.275042 0.275042)
							(end -0.3048 0.2032)
						)
						(arc
							(start -0.3048 -0.2032)
							(mid -0.275042 -0.275042)
							(end -0.2032 -0.3048)
						)
						(arc
							(start 0.2032 -0.3048)
							(mid 0.275042 -0.275042)
							(end 0.3048 -0.2032)
						)
					)
					(width 0)
					(fill yes)
				)
			)
		)
		(pad "2" smd custom
			(at 0 0.4445 180)
			(size 0.1524 0.1524)
			(layers "B.Cu" "B.Mask" "B.Paste")
			(net "GND")
			(options
				(clearance outline)
				(anchor circle)
			)
			(primitives
				(gr_poly
					(pts
						(arc
							(start 0.3048 0.2032)
							(mid 0.275042 0.275042)
							(end 0.2032 0.3048)
						)
						(arc
							(start -0.2032 0.3048)
							(mid -0.275042 0.275042)
							(end -0.3048 0.2032)
						)
						(arc
							(start -0.3048 -0.2032)
							(mid -0.275042 -0.275042)
							(end -0.2032 -0.3048)
						)
						(arc
							(start 0.2032 -0.3048)
							(mid 0.275042 -0.275042)
							(end 0.3048 -0.2032)
						)
					)
					(width 0)
					(fill yes)
				)
			)
		)
	)
	(footprint ""
		(layer "B.Cu")
		(at 19.431 -83.312 -90)
		(property "Reference" "R9P9"
			(at 0 0 90)
			(layer "B.SilkS")
			(hide yes)
			(effects
				(font
					(size 1.27 1.27)
				)
				(justify mirror)
			)
		)
		(property "Value" ""
			(at 0 0 90)
			(layer "B.Fab")
			(effects
				(font
					(size 1.27 1.27)
				)
				(justify mirror)
			)
		)
		(duplicate_pad_numbers_are_jumpers no)
		(fp_poly
			(pts
				(xy 0.2794 -0.1016) (xy -0.2794 -0.1016) (xy -0.2794 0.9906) (xy 0.2794 0.9906)
			)
			(stroke
				(width 0)
				(type default)
			)
			(fill no)
			(layer "B.CrtYd")
		)
		(fp_line
			(start -0.2794 0.9906)
			(end -0.2794 -0.1016)
			(stroke
				(width 0.1)
				(type default)
			)
			(layer "B.Fab")
		)
		(fp_line
			(start 0.2794 0.9906)
			(end -0.2794 0.9906)
			(stroke
				(width 0.1)
				(type default)
			)
			(layer "B.Fab")
		)
		(fp_line
			(start -0.2794 -0.1016)
			(end 0.2794 -0.1016)
			(stroke
				(width 0.1)
				(type default)
			)
			(layer "B.Fab")
		)
		(fp_line
			(start 0.2794 -0.1016)
			(end 0.2794 0.9906)
			(stroke
				(width 0.1)
				(type default)
			)
			(layer "B.Fab")
		)
		(pad "1" smd rect
			(at 0 0 90)
			(size 0.508 0.508)
			(layers "B.Cu" "B.Mask" "B.Paste")
			(net "A_P12V_STBY_ADR_TRIGGER")
		)
		(pad "2" smd rect
			(at 0 0.889 90)
			(size 0.508 0.508)
			(layers "B.Cu" "B.Mask" "B.Paste")
			(net "AGND_HSC")
		)
		(zone
			(layer "B.Cu")
			(hatch none 0.5)
			(connect_pads
				(clearance 0)
			)
			(min_thickness 0.25)
			(keepout
				(tracks not_allowed)
				(vias allowed)
				(pads allowed)
				(copperpour not_allowed)
				(footprints allowed)
			)
			(placement
				(enabled no)
				(sheetname "")
			)
			(fill
				(thermal_gap 0.5)
				(thermal_bridge_width 0.5)
				(island_removal_mode 0)
			)
			(polygon
				(pts
					(xy 18.796 -83.058) (xy 18.796 -83.566) (xy 19.177 -83.566) (xy 19.177 -83.058)
				)
			)
		)
		(zone
			(layer "B.Cu")
			(hatch none 0.5)
			(connect_pads
				(clearance 0)
			)
			(min_thickness 0.25)
			(keepout
				(tracks allowed)
				(vias not_allowed)
				(pads allowed)
				(copperpour not_allowed)
				(footprints allowed)
			)
			(placement
				(enabled no)
				(sheetname "")
			)
			(fill
				(thermal_gap 0.5)
				(thermal_bridge_width 0.5)
				(island_removal_mode 0)
			)
			(polygon
				(pts
					(xy 19.177 -83.058) (xy 19.177 -83.566) (xy 18.796 -83.566) (xy 18.796 -83.058)
				)
			)
		)
	)
	(footprint ""
		(layer "B.Cu")
		(at 418.846 -22.225 90)
		(property "Reference" "L25W1"
			(at 0 0 90)
			(layer "B.SilkS")
			(hide yes)
			(effects
				(font
					(size 1.27 1.27)
				)
				(justify mirror)
			)
		)
		(property "Value" "*"
			(at -0.0254 -2.8829 90)
			(unlocked yes)
			(layer "B.Fab")
			(hide yes)
			(effects
				(font
					(size 1.27 1.016)
					(thickness 0.1524)
				)
				(justify mirror)
			)
		)
		(property "Device Type" "IND-68NH-15-GP_DISCRET-GC1-INDA"
			(at -0.0254 -4.4069 90)
			(unlocked yes)
			(layer "B.Fab")
			(hide yes)
			(effects
				(font
					(size 1.27 1.016)
					(thickness 0.1524)
				)
				(justify mirror)
			)
		)
		(duplicate_pad_numbers_are_jumpers no)
		(fp_line
			(start -0.254 0)
			(end 0.254 0)
			(stroke
				(width 0.2032)
				(type default)
			)
			(layer "B.SilkS")
		)
		(fp_rect
			(start 0.5842 1.3335)
			(end -0.5842 -1.3335)
			(stroke
				(width 0)
				(type default)
			)
			(fill no)
			(layer "B.CrtYd")
		)
		(fp_rect
			(start 0.5842 1.3335)
			(end -0.5842 -1.3335)
			(stroke
				(width 0)
				(type default)
			)
			(fill no)
			(layer "B.Fab")
		)
		(pad "1" smd custom
			(at 0 -0.762 270)
			(size 0.2159 0.2159)
			(layers "B.Cu" "B.Mask" "B.Paste")
			(net "BMC_VGA_BLUE")
			(options
				(clearance outline)
				(anchor circle)
			)
			(primitives
				(gr_poly
					(pts
						(arc
							(start -0.3302 0.4318)
							(mid -0.402042 0.402042)
							(end -0.4318 0.3302)
						)
						(arc
							(start -0.4318 -0.3302)
							(mid -0.402042 -0.402042)
							(end -0.3302 -0.4318)
						)
						(arc
							(start 0.3302 -0.4318)
							(mid 0.402042 -0.402042)
							(end 0.4318 -0.3302)
						)
						(arc
							(start 0.4318 0.3302)
							(mid 0.402042 0.402042)
							(end 0.3302 0.4318)
						)
					)
					(width 0)
					(fill yes)
				)
			)
		)
		(pad "2" smd custom
			(at 0 0.762 270)
			(size 0.2159 0.2159)
			(layers "B.Cu" "B.Mask" "B.Paste")
			(net "V_IO_B_J")
			(options
				(clearance outline)
				(anchor circle)
			)
			(primitives
				(gr_poly
					(pts
						(arc
							(start -0.3302 0.4318)
							(mid -0.402042 0.402042)
							(end -0.4318 0.3302)
						)
						(arc
							(start -0.4318 -0.3302)
							(mid -0.402042 -0.402042)
							(end -0.3302 -0.4318)
						)
						(arc
							(start 0.3302 -0.4318)
							(mid 0.402042 -0.402042)
							(end 0.4318 -0.3302)
						)
						(arc
							(start 0.4318 0.3302)
							(mid 0.402042 0.402042)
							(end 0.3302 0.4318)
						)
					)
					(width 0)
					(fill yes)
				)
			)
		)
	)
)
